FILE_TYPE = CONNECTIVITY;
{Allegro Design Entry HDL 17.2-2016 S081 (4005846) 1/11/2022}
"PAGE_NUMBER" = 27;
0"NC";
1"PVDD18_S5_P0\g";
2"GND\g";
3"GND\g";
4"GND\g";
5"GND\g";
6"GND\g";
7"GND\g";
8"GND\g";
9"GND\g";
10"GND\g";
11"CPU0_BP1";
12"CPU0_BP2";
13"CPU0_BP3";
14"TP_CPU0_TEST6_CCD0";
15"TP_CPU0_TEST6_CCD1";
16"CPU0_XTRIG_R1_L7";
17"TP_CPU0_TEST6_CCD2";
18"CPU0_XTRIG_L7";
19"CPU0_XTRIG_L6";
20"CPU0_XTRIG_L5";
21"CPU0_XTRIG_L4";
22"CPU0_BP0";
23"CPU0_THERMTRIP_R_N";
24"CPU0_PROCHOT_N";
25"CPU1_THERMTRIP_R_N";
26"TP_CPU0_TEST6_CCD3";
27"JTAG_CPU0_TCK";
28"PVDD18_S5_P0\g";
29"PVDD18_S5_P0\g";
30"GND\g";
31"GND\g";
32"P3V3_STBY\g";
33"CPU0_XTRIG_R2_L4";
34"CPU0_XTRIG_R2_L5";
35"APML_CPU0_ALERT_R_N";
36"CPU0_XTRIG_R2_L6";
37"CPU0_THERMTRIP_R_N";
38"CPU0_XTRIG_R2_L7";
39"TP_CPU0_TEST47_CCD3";
40"TP_CPU0_TEST47_CCD1";
41"TP_CPU0_TEST47_CCD0";
42"TP_CPU0_TEST47_IOD0";
43"CPU0_BP1";
44"CPU0_BP0";
45"CPU0_XTRIG_R1_L6";
46"NC_CPU0_AZ_SYNC";
47"NC_CPU0_AZ_SDOUT";
48"NC_CPU0_AZ_SDIN2";
49"NC_CPU0_AZ_SDIN1";
50"NC_CPU0_AZ_SDIN0";
51"NC_CPU0_AZ_RST_N";
52"NC_CPU0_AZ_BITCLK";
53"CPU0_CORETYPE0";
54"CPU0_CORETYPE1";
55"CPU0_CORETYPE2";
56"CPU0_SP5R2";
57"CPU0_SP5R1";
58"CPU0_SP5R3";
59"CPU0_SP5R4";
60"CPU0_SA0";
61"CPU0_SA1";
62"JTAG_CPU0_TRST_N";
63"JTAG_CPU0_TDO";
64"JTAG_CPU0_TDI";
65"JTAG_CPU0_TCK";
66"JTAG_CPU0_TMS";
67"JTAG_CPU0_DBREQ_N";
68"VSENSE_VSS_SENSE_B_P0";
69"VSENSE_PVDD18_S5_P0_DN";
70"VSENSE_PVDDIO_P0_DP";
71"VSENSE_PVDDCR_CPU1_P0_DP";
72"VSENSE_VSS_SENSE_A_P0";
73"VSENSE_PVDDCR_CPU0_P0_DP";
74"VSENSE_VSS_SENSE_C_P0";
75"VSENSE_PVDD11_S3_P0_DP";
76"TP_VSENSE_PVDD33_S5_P0";
77"VSENSE_PVDDCR_SOC_P0_DP";
78"VSENSE_PVDD18_S5_P0_DP";
79"TP_CPU0_TEST47_CCD2";
80"TP_CPU0_TEST47_IOD1";
81"TP_CPU0_TEST50_IOD";
82"CPU0_CORETYPE2";
83"PRSNT_CPU0_N";
84"CPU0_CORETYPE0";
85"CPU0_CORETYPE1";
86"CPU0_SP5R1";
87"CPU0_SP5R2";
88"CPU0_SP5R3";
89"CPU0_SP5R4";
90"CPU0_SA0";
91"CPU0_SA1";
92"SVID_PVDDCR_CPU1_P0_SVD_R";
93"SVID_PVDDCR_CPU1_P0_SVC_R";
94"SVID_PVDDCR_CPU0_P0_SVD_R";
95"SVID_PVDDCR_CPU0_P0_SVC_R";
96"SVID_PVDDCR_CPU0_P0_SVD";
97"SVID_PVDDCR_CPU1_P0_SVD";
98"SVID_PVDDCR_CPU0_P0_SVC";
99"SVID_PVDDCR_CPU1_P0_SVC";
100"JTAG_CPU0_TDO";
101"JTAG_CPU0_R_TDO";
102"JTAG_CPU0_TRST_N";
103"JTAG_CPU0_TMS";
104"JTAG_CPU0_DBREQ_N";
105"JTAG_CPU0_TDI";
106"SVID_PVDDCR_CPU0_P0_SVTO";
107"SVID_PVDDCR_CPU1_P0_SVTO";
108"SMB_APML_CPU0_SCL";
109"SMB_APML_CPU0_SDA";
110"FM_P0_PCC0_N";
111"FM_P0_PCC1_N";
112"TP_UART_CPU0_UART0_RTS_N";
113"TP_CPU0_UART0_INTR";
114"UART_CPU0_UART0_R_TX";
115"FM_BIOS_USB_RECOVERY_R";
116"UART_CPU0_SCM_UART1_R_TX";
117"TP_CPU0_TEST4_IOD";
118"TP_CPU0_TEST5_IOD";
119"TP_CPU0_TEST5_CCD9";
120"TP_CPU0_TEST5_CCD10";
121"TP_CPU0_TEST5_CCD11";
122"TP_CPU0_TEST41_IDO";
123"TP_CPU0_TEST6_X3D4";
124"TP_CPU0_TEST5_CCD0";
125"TP_CPU0_TEST6_X3D5";
126"TP_CPU0_TEST5_CCD1";
127"TP_CPU0_TEST4_CCD0";
128"TP_CPU0_TEST4_CCD1";
129"TP_CPU0_TEST5_CCD3";
130"TP_CPU0_TEST4_CCD2";
131"TP_CPU0_TEST5_CCD4";
132"TP_CPU0_TEST4_CCD3";
133"TP_CPU0_TEST6_IOD";
134"TP_CPU0_TEST5_CCD5";
135"TP_CPU0_TEST4_CCD4";
136"TP_CPU0_TEST5_CCD6";
137"TP_CPU0_TEST4_CCD5";
138"TP_CPU0_TEST5_CCD7";
139"TP_CPU0_TEST4_CCD6";
140"TP_CPU0_TEST5_CCD8";
141"TP_CPU0_TEST4_CCD7";
142"TP_CPU0_TEST4_CCD8";
143"TP_CPU0_TEST4_CCD10";
144"TP_CPU0_TEST4_CCD9";
145"TP_CPU0_TEST4_CCD11";
146"TP_CPU0_TEST6_X3D0";
147"TP_CPU0_TEST6_X3D1";
148"TP_CPU0_TEST6_X3D2";
149"TP_CPU0_TEST6_X3D3";
150"TP_CPU0_TEST5_CCD2";
151"UART_CPU0_UART0_TX";
152"UART_CPU0_UART0_RX";
153"UART_CPU0_SCM_UART1_RX";
154"UART_CPU0_SCM_UART1_TX";
155"CPU0_XTRIG_L7";
156"CPU0_XTRIG_L6";
157"CPU0_XTRIG_L5";
158"CPU0_XTRIG_L4";
159"FM_BIOS_USB_RECOVERY";
160"CPU0_XTRIG_R1_L5";
161"CPU0_XTRIG_R1_L4";
162"CPU0_BP3";
163"CPU0_BP2";
164"APML_CPU0_ALERT_N";
165"CPU0_THERMTRIP_N";
166"CPU0_PROCHOT_N";
167"CPU0_BP1";
168"CPU0_BP0";
169"CPU0_BP2";
170"CPU0_BP3";
171"CPU0_XTRIG_L5";
172"CPU0_XTRIG_L4";
173"CPU0_XTRIG_L6";
174"CPU0_XTRIG_L7";
175"CPU0_THERMTRIP_N";
176"APML_CPU0_ALERT_N";
%"UNIVERSAL_POWER"
"1","(-8675,4825)","0","pure_quanta_power","I100";
;
HDL_POWER"PVDD18_S5_P0"
CDS_LIB"pure_quanta_power";
"A"1;
%"Q_RES"
"1","(-5725,4575)","2","pure_quanta","I170";
;
LOCATION"R404"
$SEC"1"
CDS_SEC"1"
VALUE"0"
CDS_LIB"pure_quanta"
WATTAGE"1/16W"
MATERIAL"CHIP"
TOLERANCE"5%"
PART_NUMBER"CS00002JB38"
PACK_TYPE"0402LF";
"B"
$PN"2"100;
"A"
$PN"1"101;
%"GENOA_SP5"
"20","(-4275,3500)","0","pure_quanta","I227";
;
LOCATION"U25"
$SEC"20"
CDS_SEC"20"
PART_TYPE"SMLF"
MATERIAL"IO"
VALUE"SOCKET6096_13568-001"
PART_NUMBER"DGA^6000030"
CDS_LIB"pure_quanta"
CDS_LMAN_SYM_OUTLINE"-600,2425,600,-2425"
NEEDS_NO_SIZE"TRUE";
"CORETYPE2"
$PN"D68"82;
"BP3"
$PN"A62"13;
"BP2"
$PN"A63"12;
"BP1"
$PN"C62"11;
"BP0"
$PN"C63"22;
"TEST41_IOD"
$PN"W31"122;
"TEST47_CCD3"
$PN"E32"39;
"TEST6_CCD0"
$PN"AA46"14;
"TEST6_X3D3"
$PN"CJ52"149;
"TEST6_X3D2"
$PN"AA29"148;
"TEST47_IOD1"
$PN"D7"80;
"TEST6_X3D1"
$PN"CJ29"147;
"TEST47_IOD0"
$PN"B58"42;
"TEST6_X3D0"
$PN"AA47"146;
"TEST5_CCD11"
$PN"Y29"121;
"TEST4_CCD11"
$PN"AA28"145;
"TEST5_CCD10"
$PN"CK47"120;
"TEST4_CCD9"
$PN"CK30"144;
"TEST4_CCD10"
$PN"CJ47"143;
"TEST47_CCD2"
$PN"CK46"79;
"TEST4_CCD8"
$PN"AA48"142;
"TEST5_CCD9"
$PN"CK29"119;
"TEST47_CCD1"
$PN"CJ24"40;
"TEST4_CCD7"
$PN"AA27"141;
"TEST50_IOD"
$PN"B61"81;
"TEST5_CCD8"
$PN"Y47"140;
"TEST47_CCD0"
$PN"B60"41;
"TEST4_CCD6"
$PN"CJ50"139;
"TEST5_CCD7"
$PN"AA26"138;
"TEST4_CCD5"
$PN"CJ26"137;
"TEST5_CCD6"
$PN"CJ51"136;
"TEST4_CCD4"
$PN"AA52"135;
"TEST5_CCD5"
$PN"CJ25"134;
"TEST6_IOD"
$PN"AA49"133;
"TEST4_CCD3"
$PN"AA30"132;
"TEST5_CCD4"
$PN"AA53"131;
"TEST5_IOD"
$PN"AA24"118;
"TEST4_CCD2"
$PN"CJ48"130;
"TEST4_IOD"
$PN"AA25"117;
"TEST5_CCD3"
$PN"Y30"129;
"TEST4_CCD1"
$PN"CJ28"128;
"TEST5_CCD2"
$PN"CJ49"150;
"TEST6_CCD3"
$PN"Y46"26;
"TEST4_CCD0"
$PN"AA50"127;
"TEST5_CCD1"
$PN"CJ27"126;
"TEST6_CCD2"
$PN"CJ46"17;
"TEST6_X3D5"
$PN"CJ53"125;
"TEST5_CCD0"
$PN"AA51"124;
"TEST6_CCD1"
$PN"CJ30"15;
"TEST6_X3D4"
$PN"AA23"123;
"VDDCR_CPU0_SENSE"
$PN"C2"73;
"VDDCR_CPU1_SENSE"
$PN"DG3"71;
"VDDCR_SOC_SENSE"
$PN"B3"77;
"VDD_33_S5_SENSE"
$PN"BP53"76;
"VDD_18_S5_SENSE"
$PN"C74"78;
"VDD_11_S3_SENSE"
$PN"DH3"75;
"VDDIO_SENSE"
$PN"BR53"70;
"VSS_SENSE_D"
$PN"B73"69;
"VSS_SENSE_C"
$PN"DJ3"74;
"VSS_SENSE_B"
$PN"BR54"68;
"VSS_SENSE_A"
$PN"C3"72;
"UART1_TXD||AGPIO142"
$PN"DJ32"116;
"UART1_RXD||AGPIO141"
$PN"DH33"153;
"RTC_LDO_SELECT"
$PN"DH8"4;
"TCK"
$PN"B17"27;
"SP5R1"
$PN"C19"86;
"AZ_SDIN1||SW_MCLK"
$PN"D33"49;
"AZ_SDIN0||SW_MDATA3"
$PN"C33"50;
"AZ_RST_L||SW_MDATA1"
$PN"A34"51;
"AZ_SDOUT||SW_MDATA2"
$PN"A32"47;
"AZ_SDIN2||SW_MDATA0"
$PN"A33"48;
"UART0_CTS_L||UART2_TXD||AGPIO135"
$PN"DJ33"115;
"UART0_TXD||AGPIO138"
$PN"DJ34"114;
"UART0_INTR||AGPIO139"
$PN"DG34"113;
"UART0_RTS_L||UART2_RXD||AGPIO137"
$PN"DF34"112;
"UART0_RXD||AGPIO136"
$PN"DG35"152;
"SVC1"
$PN"DJ72"99;
"SVT1"
$PN"DG73"107;
"SVC0"
$PN"A23"98;
"SVD1"
$PN"DH72"97;
"SVT0"
$PN"B21"106;
"SVD0"
$PN"A22"96;
"AZ_SYNC"
$PN"D32"46;
"AZ_BITCLK"
$PN"C32"52;
"PCC1_L \B"
$PN"DG72"111;
"PCC0_L \B"
$PN"C22"110;
"SP5R4"
$PN"DH10"89;
"SP5R3"
$PN"DH73"88;
"SP5R2"
$PN"C68"87;
"CORETYPE1"
$PN"B69"85;
"CORETYPE0"
$PN"C70"84;
"SA1"
$PN"DJ56"91;
"XTRIG_L7 \B"
$PN"A65"38;
"XTRIG_L6 \B"
$PN"A66"36;
"XTRIG_L5 \B"
$PN"C65"34;
"XTRIG_L4 \B"
$PN"C66"33;
"TRST_L \B"
$PN"A17"102;
"TMS"
$PN"A16"103;
"THERMTRIP_L \B"
$PN"DJ9"165;
"TDO"
$PN"C18"101;
"TDI"
$PN"C17"105;
"SID"
$PN"DH71"109;
"SIC"
$PN"DJ71"108;
"SA0"
$PN"DJ55"90;
"PROCHOT_L \B"
$PN"A69"166;
"DBREQ_L \B"
$PN"C16"104;
"CPU_PRESENT_L"
$PN"B66"83;
"ALERT_L \B"
$PN"A68"164;
%"UNIVERSAL_POWER"
"1","(-225,5925)","0","pure_quanta_power","I231";
;
HDL_POWER"PVDD18_S5_P0"
CDS_LIB"pure_quanta_power";
"A"28;
%"SCONN8_G802M0083150RD3EU"
"1","(-500,2875)","0","pure_quanta","I266";
;
LOCATION"J5"
$SEC"1"
CDS_SEC"1"
PART_TYPE"SMLF"
MATERIAL"IO"
VALUE"SCONN8_G802M0083150RD3EU"
PART_NUMBER"DFHD08MS351"
CDS_LMAN_SYM_OUTLINE"-125,125,125,-125"
NEEDS_NO_SIZE"TRUE"
CDS_LIB"pure_quanta";
"8"
$PN"8"30;
"7"
$PN"7"16;
"6"
$PN"6"30;
"5"
$PN"5"45;
"4"
$PN"4"30;
"3"
$PN"3"160;
"2"
$PN"2"30;
"1"
$PN"1"161;
%"Q_RES"
"1","(-2375,1475)","2","pure_quanta","I279";
;
LOCATION"R405"
$SEC"1"
CDS_SEC"1"
VALUE"0"
CDS_LIB"pure_quanta"
WATTAGE"1/16W"
MATERIAL"CHIP"
TOLERANCE"5%"
PART_NUMBER"CS00002JB38"
PACK_TYPE"0402LF";
"B"
$PN"2"114;
"A"
$PN"1"151;
%"SCONN8_G802M0083150RD3EU"
"1","(-500,2250)","0","pure_quanta","I282";
;
LOCATION"J48"
$SEC"1"
CDS_SEC"1"
PART_TYPE"SMLF"
MATERIAL"IO"
VALUE"SCONN8_G802M0083150RD3EU"
PART_NUMBER"DFHD08MS351"
CDS_LIB"pure_quanta"
NEEDS_NO_SIZE"TRUE"
CDS_LMAN_SYM_OUTLINE"-125,125,125,-125";
"8"
$PN"8"31;
"7"
$PN"7"162;
"6"
$PN"6"31;
"5"
$PN"5"163;
"4"
$PN"4"31;
"3"
$PN"3"43;
"2"
$PN"2"31;
"1"
$PN"1"44;
%"Q_RES"
"1","(-2375,1375)","0","pure_quanta","I288";
;
LOCATION"R2318"
$SEC"1"
CDS_SEC"1"
VALUE"0"
CDS_LIB"pure_quanta"
WATTAGE"1/16W"
MATERIAL"CHIP"
TOLERANCE"5%"
PART_NUMBER"CS00002JB38"
PACK_TYPE"0402LF";
"B"
$PN"2"154;
"A"
$PN"1"116;
%"UNIVERSAL_POWER"
"1","(-8000,1575)","0","pure_quanta_power","I293";
;
HDL_POWER"PVDD18_S5_P0"
CDS_LIB"pure_quanta_power";
"A"29;
%"Q_RES"
"2","(-6375,1300)","0","pure_quanta","I294";
;
LOCATION"R403"
$SEC"1"
CDS_SEC"1"
WATTAGE"1/16W"
MATERIAL"CHIP"
TOLERANCE"5%"
VALUE"1K"
PACK_TYPE"0402LF"
CDS_LIB"pure_quanta"
PART_NUMBER"TMP_QCS21002JB34";
"A"
$PN"1"29;
"B"
$PN"2"67;
%"Q_CAP"
"1","(-6375,600)","0","pure_quanta","I295";
;
LOCATION"C212"
$SEC"1"
CDS_SEC"1"
MATERIAL"EMPTY"
TOLERANCE"10%"
VALUE"0.001UF"
PART_NUMBER"CH30106KB19"
VOLTAGE"50V"
PACK_TYPE"C0402"
CDS_LIB"pure_quanta";
"B"
$PN"2"2;
"A"
$PN"1"67;
%"Q_RES"
"2","(-6675,1300)","0","pure_quanta","I296";
;
LOCATION"R402"
$SEC"1"
CDS_SEC"1"
WATTAGE"1/16W"
MATERIAL"CHIP"
TOLERANCE"5%"
VALUE"1K"
PACK_TYPE"0402LF"
CDS_LIB"pure_quanta"
PART_NUMBER"TMP_QCS21002JB34";
"A"
$PN"1"29;
"B"
$PN"2"66;
%"Q_CAP"
"1","(-6675,600)","0","pure_quanta","I297";
;
LOCATION"C211"
$SEC"1"
CDS_SEC"1"
MATERIAL"EMPTY"
TOLERANCE"10%"
VALUE"0.001UF"
VOLTAGE"50V"
PACK_TYPE"C0402"
CDS_LIB"pure_quanta"
PART_NUMBER"CH30106KB19";
"B"
$PN"2"3;
"A"
$PN"1"66;
%"GND"
"1","(-6375,300)","0","pure_quanta_power","I298";
;
SIZE"1B"
CDS_LIB"pure_quanta_power"
HDL_POWER"GND";
"A<SIZE-1..0>\NAC"2;
%"GND"
"1","(-6675,300)","0","pure_quanta_power","I299";
;
SIZE"1B"
CDS_LIB"pure_quanta_power"
HDL_POWER"GND";
"A<SIZE-1..0>\NAC"3;
%"UNIVERSAL_GND"
"1","(-5250,975)","0","pure_quanta_power","I3";
;
CDS_LIB"pure_quanta_power"
HDL_POWER"GND";
"A"4;
%"Q_RES"
"2","(-7025,1300)","0","pure_quanta","I300";
;
LOCATION"R401"
$SEC"1"
CDS_SEC"1"
WATTAGE"1/16W"
MATERIAL"CHIP"
TOLERANCE"5%"
VALUE"1K"
PACK_TYPE"0402LF"
CDS_LIB"pure_quanta"
PART_NUMBER"TMP_QCS21002JB34";
"A"
$PN"1"29;
"B"
$PN"2"65;
%"Q_RES"
"2","(-7350,1300)","0","pure_quanta","I301";
;
LOCATION"R400"
$SEC"1"
CDS_SEC"1"
WATTAGE"1/16W"
MATERIAL"CHIP"
TOLERANCE"5%"
VALUE"1K"
PACK_TYPE"0402LF"
CDS_LIB"pure_quanta"
PART_NUMBER"TMP_QCS21002JB34";
"A"
$PN"1"29;
"B"
$PN"2"62;
%"Q_CAP"
"1","(-7025,600)","0","pure_quanta","I302";
;
LOCATION"C210"
$SEC"1"
CDS_SEC"1"
MATERIAL"EMPTY"
TOLERANCE"10%"
VALUE"0.001UF"
VOLTAGE"50V"
PACK_TYPE"C0402"
CDS_LIB"pure_quanta"
PART_NUMBER"CH30106KB19";
"B"
$PN"2"6;
"A"
$PN"1"65;
%"Q_CAP"
"1","(-7350,600)","0","pure_quanta","I303";
;
LOCATION"C209"
$SEC"1"
CDS_SEC"1"
MATERIAL"EMPTY"
TOLERANCE"10%"
VALUE"0.001UF"
VOLTAGE"50V"
PACK_TYPE"C0402"
CDS_LIB"pure_quanta"
PART_NUMBER"CH30106KB19";
"B"
$PN"2"5;
"A"
$PN"1"62;
%"Q_RES"
"2","(-7675,1300)","0","pure_quanta","I304";
;
LOCATION"R399"
$SEC"1"
CDS_SEC"1"
WATTAGE"1/16W"
MATERIAL"CHIP"
TOLERANCE"5%"
VALUE"1K"
PACK_TYPE"0402LF"
CDS_LIB"pure_quanta"
PART_NUMBER"TMP_QCS21002JB34";
"A"
$PN"1"29;
"B"
$PN"2"64;
%"Q_RES"
"2","(-8000,1300)","0","pure_quanta","I305";
;
LOCATION"R398"
$SEC"1"
CDS_SEC"1"
WATTAGE"1/16W"
MATERIAL"CHIP"
TOLERANCE"5%"
VALUE"1K"
PACK_TYPE"0402LF"
CDS_LIB"pure_quanta"
PART_NUMBER"TMP_QCS21002JB34";
"A"
$PN"1"29;
"B"
$PN"2"63;
%"Q_CAP"
"1","(-7675,600)","0","pure_quanta","I306";
;
LOCATION"C208"
$SEC"1"
CDS_SEC"1"
MATERIAL"EMPTY"
TOLERANCE"10%"
VALUE"0.001UF"
VOLTAGE"50V"
PACK_TYPE"C0402"
CDS_LIB"pure_quanta"
PART_NUMBER"CH30106KB19";
"B"
$PN"2"8;
"A"
$PN"1"64;
%"Q_CAP"
"1","(-8000,600)","0","pure_quanta","I307";
;
LOCATION"C207"
$SEC"1"
CDS_SEC"1"
MATERIAL"EMPTY"
TOLERANCE"10%"
VALUE"0.001UF"
VOLTAGE"50V"
PACK_TYPE"C0402"
CDS_LIB"pure_quanta"
PART_NUMBER"CH30106KB19";
"B"
$PN"2"7;
"A"
$PN"1"63;
%"GND"
"1","(-7350,300)","0","pure_quanta_power","I308";
;
SIZE"1B"
CDS_LIB"pure_quanta_power"
HDL_POWER"GND";
"A<SIZE-1..0>\NAC"5;
%"GND"
"1","(-7025,300)","0","pure_quanta_power","I309";
;
SIZE"1B"
CDS_LIB"pure_quanta_power"
HDL_POWER"GND";
"A<SIZE-1..0>\NAC"6;
%"GND"
"1","(-8000,300)","0","pure_quanta_power","I310";
;
SIZE"1B"
CDS_LIB"pure_quanta_power"
HDL_POWER"GND";
"A<SIZE-1..0>\NAC"7;
%"GND"
"1","(-7675,300)","0","pure_quanta_power","I311";
;
CDS_LIB"pure_quanta_power"
SIZE"1B"
HDL_POWER"GND";
"A<SIZE-1..0>\NAC"8;
%"Q_RES"
"1","(-6350,5325)","0","pure_quanta","I318";
;
LOCATION"PR59"
$SEC"1"
CDS_SEC"1"
VALUE"0"
CDS_LIB"pure_quanta"
WATTAGE"1/16W"
MATERIAL"CHIP"
TOLERANCE"5%"
PART_NUMBER"CS00002JB38"
PACK_TYPE"0402LF";
"B"
$PN"2"99;
"A"
$PN"1"93;
%"Q_RES"
"1","(-6350,5275)","0","pure_quanta","I319";
;
LOCATION"PR60"
$SEC"1"
CDS_SEC"1"
VALUE"0"
CDS_LIB"pure_quanta"
WATTAGE"1/16W"
MATERIAL"CHIP"
TOLERANCE"5%"
PART_NUMBER"CS00002JB38"
PACK_TYPE"0402LF";
"B"
$PN"2"97;
"A"
$PN"1"92;
%"Q_RES"
"1","(-6350,5475)","0","pure_quanta","I322";
;
LOCATION"PR303"
$SEC"1"
CDS_SEC"1"
VALUE"0"
CDS_LIB"pure_quanta"
WATTAGE"1/16W"
MATERIAL"CHIP"
TOLERANCE"5%"
PART_NUMBER"CS00002JB38"
PACK_TYPE"0402LF";
"B"
$PN"2"96;
"A"
$PN"1"94;
%"Q_RES"
"1","(-6350,5525)","0","pure_quanta","I323";
;
LOCATION"PR302"
$SEC"1"
CDS_SEC"1"
VALUE"0"
CDS_LIB"pure_quanta"
WATTAGE"1/16W"
MATERIAL"CHIP"
TOLERANCE"5%"
PART_NUMBER"CS00002JB38"
PACK_TYPE"0402LF";
"B"
$PN"2"98;
"A"
$PN"1"95;
%"Q_RES"
"1","(-1475,2900)","0","pure_quanta","I334";
;
LOCATION"R483"
$SEC"1"
CDS_SEC"1"
VALUE"0"
CDS_LIB"pure_quanta"
WATTAGE"1/16W"
MATERIAL"CHIP"
TOLERANCE"5%"
PART_NUMBER"CS00002JB38"
PACK_TYPE"0402LF";
"B"
$PN"2"160;
"A"
$PN"1"157;
%"Q_RES"
"1","(-1475,2950)","0","pure_quanta","I335";
;
LOCATION"R481"
$SEC"1"
CDS_SEC"1"
VALUE"0"
CDS_LIB"pure_quanta"
WATTAGE"1/16W"
MATERIAL"CHIP"
TOLERANCE"5%"
PART_NUMBER"CS00002JB38"
PACK_TYPE"0402LF";
"B"
$PN"2"161;
"A"
$PN"1"158;
%"Q_RES"
"1","(-1475,2850)","0","pure_quanta","I336";
;
LOCATION"R484"
$SEC"1"
CDS_SEC"1"
VALUE"0"
CDS_LIB"pure_quanta"
WATTAGE"1/16W"
MATERIAL"CHIP"
TOLERANCE"5%"
PART_NUMBER"CS00002JB38"
PACK_TYPE"0402LF";
"B"
$PN"2"45;
"A"
$PN"1"156;
%"Q_RES"
"1","(-1475,2800)","0","pure_quanta","I337";
;
LOCATION"R485"
$SEC"1"
CDS_SEC"1"
VALUE"0"
CDS_LIB"pure_quanta"
WATTAGE"1/16W"
MATERIAL"CHIP"
TOLERANCE"5%"
PART_NUMBER"CS00002JB38"
PACK_TYPE"0402LF";
"B"
$PN"2"16;
"A"
$PN"1"155;
%"Q_RES"
"1","(-2725,4575)","0","pure_quanta","I346";
;
LOCATION"R156"
$SEC"1"
CDS_SEC"1"
VALUE"0"
CDS_LIB"pure_quanta"
WATTAGE"1/16W"
MATERIAL"CHIP"
TOLERANCE"5%"
PART_NUMBER"CS00002JB38"
PACK_TYPE"0402LF";
"B"
$PN"2"21;
"A"
$PN"1"33;
%"Q_RES"
"1","(-2725,4525)","0","pure_quanta","I347";
;
LOCATION"R157"
$SEC"1"
CDS_SEC"1"
VALUE"0"
CDS_LIB"pure_quanta"
WATTAGE"1/16W"
MATERIAL"CHIP"
TOLERANCE"5%"
PART_NUMBER"CS00002JB38"
PACK_TYPE"0402LF";
"B"
$PN"2"20;
"A"
$PN"1"34;
%"Q_RES"
"1","(-2725,4425)","0","pure_quanta","I348";
;
LOCATION"R357"
$SEC"1"
CDS_SEC"1"
VALUE"0"
CDS_LIB"pure_quanta"
PACK_TYPE"0402LF"
PART_NUMBER"CS00002JB38"
TOLERANCE"5%"
MATERIAL"CHIP"
WATTAGE"1/16W";
"B"
$PN"2"18;
"A"
$PN"1"38;
%"Q_RES"
"1","(-2725,4475)","0","pure_quanta","I349";
;
LOCATION"R356"
$SEC"1"
CDS_SEC"1"
VALUE"0"
CDS_LIB"pure_quanta"
WATTAGE"1/16W"
MATERIAL"CHIP"
TOLERANCE"5%"
PART_NUMBER"CS00002JB38"
PACK_TYPE"0402LF";
"B"
$PN"2"19;
"A"
$PN"1"36;
%"Q_RES"
"1","(-2500,1625)","0","pure_quanta","I353";
;
LOCATION"R1204"
$SEC"1"
CDS_SEC"1"
VALUE"0"
CDS_LIB"pure_quanta"
WATTAGE"1/16W"
MATERIAL"CHIP"
TOLERANCE"5%"
PART_NUMBER"CS00002JB38"
PACK_TYPE"0402LF";
"B"
$PN"2"159;
"A"
$PN"1"115;
%"TP"
"1","(-5975,1625)","6","pure_quanta","I355";
;
LOCATION"TP9"
$SEC"1"
CDS_SEC"1"
MATERIAL"NA"
CDS_LIB"pure_quanta"
PART_NUMBER"TP30"
PACK_TYPE"TP";
"TP \B"
$PN"1"
$PIN_NUMBER"?"78;
%"TP"
"1","(-6125,1625)","6","pure_quanta","I356";
;
LOCATION"TP8"
$SEC"1"
CDS_SEC"1"
MATERIAL"NA"
CDS_LIB"pure_quanta"
PART_NUMBER"TP30"
PACK_TYPE"TP";
"TP \B"
$PN"1"
$PIN_NUMBER"?"75;
%"TP"
"1","(-6200,1625)","6","pure_quanta","I357";
;
LOCATION"TP7"
$SEC"1"
CDS_SEC"1"
MATERIAL"NA"
CDS_LIB"pure_quanta"
PART_NUMBER"TP30"
PACK_TYPE"TP";
"TP \B"
$PN"1"
$PIN_NUMBER"?"73;
%"TP"
"1","(-6275,1625)","6","pure_quanta","I358";
;
LOCATION"TP6"
$SEC"1"
CDS_SEC"1"
MATERIAL"NA"
CDS_LIB"pure_quanta"
PART_NUMBER"TP30"
PACK_TYPE"TP";
"TP \B"
$PN"1"
$PIN_NUMBER"?"71;
%"TP"
"1","(-6350,1625)","6","pure_quanta","I359";
;
LOCATION"TP5"
$SEC"1"
CDS_SEC"1"
MATERIAL"NA"
CDS_LIB"pure_quanta"
PART_NUMBER"TP30"
PACK_TYPE"TP";
"TP \B"
$PN"1"
$PIN_NUMBER"?"70;
%"TP"
"1","(-6475,1625)","6","pure_quanta","I360";
;
LOCATION"TP4"
$SEC"1"
CDS_SEC"1"
MATERIAL"NA"
CDS_LIB"pure_quanta"
PART_NUMBER"TP30"
PACK_TYPE"TP";
"TP \B"
$PN"1"
$PIN_NUMBER"?"69;
%"TP"
"1","(-6550,1625)","6","pure_quanta","I361";
;
LOCATION"TP3"
$SEC"1"
CDS_SEC"1"
MATERIAL"NA"
CDS_LIB"pure_quanta"
PART_NUMBER"TP30"
PACK_TYPE"TP";
"TP \B"
$PN"1"
$PIN_NUMBER"?"74;
%"TP"
"1","(-6625,1625)","6","pure_quanta","I362";
;
LOCATION"TP2"
$SEC"1"
CDS_SEC"1"
MATERIAL"NA"
CDS_LIB"pure_quanta"
PART_NUMBER"TP30"
PACK_TYPE"TP";
"TP \B"
$PN"1"
$PIN_NUMBER"?"68;
%"UNIVERSAL_GND"
"1","(-150,2650)","0","pure_quanta_power","I364";
;
CDS_LIB"pure_quanta_power"
HDL_POWER"GND";
"A"30;
%"UNIVERSAL_GND"
"1","(-150,2025)","0","pure_quanta_power","I365";
;
CDS_LIB"pure_quanta_power"
HDL_POWER"GND";
"A"31;
%"UNIVERSAL_POWER"
"1","(-9050,3400)","0","pure_quanta_power","I366";
;
HDL_POWER"P3V3_STBY"
CDS_LIB"pure_quanta_power";
"A"32;
%"Q_RES"
"1","(-575,5400)","0","pure_quanta","I377";
;
LOCATION"R412"
$SEC"1"
CDS_SEC"1"
VALUE"2.2K"
CDS_LIB"pure_quanta"
WATTAGE"1/16W"
MATERIAL"CHIP"
TOLERANCE"5%"
PART_NUMBER"CS22202JB07"
PACK_TYPE"0402LF";
"B"
$PN"2"28;
"A"
$PN"1"24;
%"Q_RES"
"1","(-575,5100)","0","pure_quanta","I378";
;
LOCATION"R418"
$SEC"1"
CDS_SEC"1"
VALUE"2.2K"
CDS_LIB"pure_quanta"
WATTAGE"1/16W"
MATERIAL"CHIP"
TOLERANCE"5%"
PART_NUMBER"CS22202JB07"
PACK_TYPE"0402LF";
"B"
$PN"2"28;
"A"
$PN"1"176;
%"Q_RES"
"1","(-575,5150)","0","pure_quanta","I379";
;
LOCATION"R417"
$SEC"1"
CDS_SEC"1"
VALUE"2.2K"
CDS_LIB"pure_quanta"
WATTAGE"1/16W"
MATERIAL"CHIP"
TOLERANCE"5%"
PART_NUMBER"CS22202JB07"
PACK_TYPE"0402LF";
"B"
$PN"2"28;
"A"
$PN"1"175;
%"Q_RES"
"1","(-575,5600)","0","pure_quanta","I380";
;
LOCATION"R408"
$SEC"1"
CDS_SEC"1"
VALUE"2.2K"
CDS_LIB"pure_quanta"
WATTAGE"1/16W"
MATERIAL"CHIP"
TOLERANCE"5%"
PART_NUMBER"CS22202JB07"
PACK_TYPE"0402LF";
"B"
$PN"2"28;
"A"
$PN"1"168;
%"Q_RES"
"1","(-575,5550)","0","pure_quanta","I381";
;
LOCATION"R409"
$SEC"1"
CDS_SEC"1"
VALUE"2.2K"
CDS_LIB"pure_quanta"
WATTAGE"1/16W"
MATERIAL"CHIP"
TOLERANCE"5%"
PART_NUMBER"CS22202JB07"
PACK_TYPE"0402LF";
"B"
$PN"2"28;
"A"
$PN"1"167;
%"Q_RES"
"1","(-575,5500)","0","pure_quanta","I382";
;
LOCATION"R410"
$SEC"1"
CDS_SEC"1"
VALUE"2.2K"
CDS_LIB"pure_quanta"
WATTAGE"1/16W"
MATERIAL"CHIP"
TOLERANCE"5%"
PART_NUMBER"CS22202JB07"
PACK_TYPE"0402LF";
"B"
$PN"2"28;
"A"
$PN"1"169;
%"Q_RES"
"1","(-575,5450)","0","pure_quanta","I383";
;
LOCATION"R411"
$SEC"1"
CDS_SEC"1"
VALUE"2.2K"
CDS_LIB"pure_quanta"
WATTAGE"1/16W"
MATERIAL"CHIP"
TOLERANCE"5%"
PART_NUMBER"CS22202JB07"
PACK_TYPE"0402LF";
"B"
$PN"2"28;
"A"
$PN"1"170;
%"Q_RES"
"1","(-575,5350)","0","pure_quanta","I384";
;
LOCATION"R413"
$SEC"1"
CDS_SEC"1"
VALUE"2.2K"
CDS_LIB"pure_quanta"
WATTAGE"1/16W"
MATERIAL"CHIP"
TOLERANCE"5%"
PART_NUMBER"CS22202JB07"
PACK_TYPE"0402LF";
"B"
$PN"2"28;
"A"
$PN"1"172;
%"Q_RES"
"1","(-575,5300)","0","pure_quanta","I385";
;
LOCATION"R414"
$SEC"1"
CDS_SEC"1"
VALUE"2.2K"
CDS_LIB"pure_quanta"
WATTAGE"1/16W"
MATERIAL"CHIP"
TOLERANCE"5%"
PART_NUMBER"CS22202JB07"
PACK_TYPE"0402LF";
"B"
$PN"2"28;
"A"
$PN"1"171;
%"Q_RES"
"1","(-575,5250)","0","pure_quanta","I386";
;
LOCATION"R415"
$SEC"1"
CDS_SEC"1"
VALUE"2.2K"
CDS_LIB"pure_quanta"
WATTAGE"1/16W"
MATERIAL"CHIP"
TOLERANCE"5%"
PART_NUMBER"CS22202JB07"
PACK_TYPE"0402LF";
"B"
$PN"2"28;
"A"
$PN"1"173;
%"Q_RES"
"1","(-575,5200)","0","pure_quanta","I387";
;
LOCATION"R416"
$SEC"1"
CDS_SEC"1"
VALUE"2.2K"
CDS_LIB"pure_quanta"
WATTAGE"1/16W"
MATERIAL"CHIP"
TOLERANCE"5%"
PART_NUMBER"CS22202JB07"
PACK_TYPE"0402LF";
"B"
$PN"2"28;
"A"
$PN"1"174;
%"Q_RES"
"1","(-8700,2850)","0","pure_quanta","I388";
;
LOCATION"R387"
$SEC"1"
CDS_SEC"1"
VALUE"2.2K"
CDS_LIB"pure_quanta"
WATTAGE"1/16W"
MATERIAL"CHIP"
TOLERANCE"5%"
PART_NUMBER"CS22202JB07"
PACK_TYPE"0402LF";
"B"
$PN"2"55;
"A"
$PN"1"32;
%"Q_RES"
"1","(-8700,2900)","0","pure_quanta","I389";
;
LOCATION"R388"
$SEC"1"
CDS_SEC"1"
VALUE"2.2K"
CDS_LIB"pure_quanta"
WATTAGE"1/16W"
MATERIAL"CHIP"
TOLERANCE"5%"
PART_NUMBER"CS22202JB07"
PACK_TYPE"0402LF";
"B"
$PN"2"54;
"A"
$PN"1"32;
%"Q_RES"
"1","(-8700,2950)","0","pure_quanta","I390";
;
LOCATION"R390"
$SEC"1"
CDS_SEC"1"
VALUE"2.2K"
CDS_LIB"pure_quanta"
WATTAGE"1/16W"
MATERIAL"CHIP"
TOLERANCE"5%"
PART_NUMBER"CS22202JB07"
PACK_TYPE"0402LF";
"B"
$PN"2"53;
"A"
$PN"1"32;
%"Q_RES"
"1","(-8700,3000)","0","pure_quanta","I391";
;
LOCATION"R389"
$SEC"1"
CDS_SEC"1"
VALUE"2.2K"
CDS_LIB"pure_quanta"
WATTAGE"1/16W"
MATERIAL"CHIP"
TOLERANCE"5%"
PART_NUMBER"CS22202JB07"
PACK_TYPE"0402LF";
"B"
$PN"2"59;
"A"
$PN"1"32;
%"Q_RES"
"1","(-8700,3050)","0","pure_quanta","I392";
;
LOCATION"R391"
$SEC"1"
CDS_SEC"1"
VALUE"2.2K"
CDS_LIB"pure_quanta"
WATTAGE"1/16W"
MATERIAL"CHIP"
TOLERANCE"5%"
PART_NUMBER"CS22202JB07"
PACK_TYPE"0402LF";
"B"
$PN"2"58;
"A"
$PN"1"32;
%"Q_RES"
"1","(-8700,3100)","0","pure_quanta","I393";
;
LOCATION"R396"
$SEC"1"
CDS_SEC"1"
VALUE"2.2K"
CDS_LIB"pure_quanta"
WATTAGE"1/16W"
MATERIAL"CHIP"
TOLERANCE"5%"
PART_NUMBER"CS22202JB07"
PACK_TYPE"0402LF";
"B"
$PN"2"56;
"A"
$PN"1"32;
%"Q_RES"
"1","(-8700,3150)","0","pure_quanta","I394";
;
LOCATION"R397"
$SEC"1"
CDS_SEC"1"
VALUE"2.2K"
CDS_LIB"pure_quanta"
WATTAGE"1/16W"
MATERIAL"CHIP"
TOLERANCE"5%"
PART_NUMBER"CS22202JB07"
PACK_TYPE"0402LF";
"B"
$PN"2"57;
"A"
$PN"1"32;
%"Q_RES"
"2","(-8675,4650)","2","pure_quanta","I395";
;
LOCATION"R392"
$SEC"1"
CDS_SEC"1"
MATERIAL"EMPTY"
VALUE"2.2K"
PACK_TYPE"0402LF"
CDS_LIB"pure_quanta"
WATTAGE"1/16W"
TOLERANCE"5%"
PART_NUMBER"CS22202JB07";
"A"
$PN"1"1;
"B"
$PN"2"60;
%"Q_RES"
"2","(-8675,4350)","2","pure_quanta","I396";
;
LOCATION"R393"
$SEC"1"
CDS_SEC"1"
MATERIAL"CHIP"
VALUE"2.2K"
PACK_TYPE"0402LF"
CDS_LIB"pure_quanta"
WATTAGE"1/16W"
TOLERANCE"5%"
PART_NUMBER"CS22202JB07";
"A"
$PN"1"60;
"B"
$PN"2"10;
%"Q_RES"
"2","(-8550,4350)","0","pure_quanta","I397";
;
LOCATION"R394"
$SEC"1"
CDS_SEC"1"
MATERIAL"CHIP"
VALUE"2.2K"
PACK_TYPE"0402LF"
CDS_LIB"pure_quanta"
WATTAGE"1/16W"
TOLERANCE"5%"
PART_NUMBER"CS22202JB07";
"A"
$PN"1"61;
"B"
$PN"2"9;
%"Q_RES"
"1","(-2725,4725)","0","pure_quanta","I399";
;
LOCATION"R489"
$SEC"1"
CDS_SEC"1"
VALUE"33"
BOM_COST"MEM"
CDS_LIB"pure_quanta"
WATTAGE"1/16W"
MATERIAL"CHIP"
TOLERANCE"5%"
PART_NUMBER"CS03302JB29"
PACK_TYPE"0402LF"
ROOM"RST_CPU0_PLD_TO_DIMM";
"B"
$PN"2"37;
"A"
$PN"1"165;
%"Q_RES"
"1","(-2725,4875)","0","pure_quanta","I401";
;
LOCATION"R247"
$SEC"1"
CDS_SEC"1"
VALUE"33"
CDS_LIB"pure_quanta"
BOM_COST"MEM"
WATTAGE"1/16W"
MATERIAL"CHIP"
TOLERANCE"5%"
PART_NUMBER"CS03302JB29"
PACK_TYPE"0402LF"
ROOM"RST_CPU0_PLD_TO_DIMM";
"B"
$PN"2"35;
"A"
$PN"1"164;
%"TP"
"1","(-5900,1625)","4","pure_quanta","I403";
;
LOCATION"TP10"
$SEC"1"
CDS_SEC"1"
MATERIAL"NA"
CDS_LIB"pure_quanta"
PART_NUMBER"TP26"
PACK_TYPE"TP";
"TP \B"
$PN"1"
$PIN_NUMBER"?"77;
%"TP"
"1","(-6700,1625)","4","pure_quanta","I404";
;
LOCATION"TP1"
$SEC"1"
CDS_SEC"1"
MATERIAL"NA"
CDS_LIB"pure_quanta"
PART_NUMBER"TP26"
PACK_TYPE"TP";
"TP \B"
$PN"1"
$PIN_NUMBER"?"72;
%"Q_RES"
"1","(-1050,3825)","0","pure_quanta","I407";
;
$LOCATION"R1533"
CDS_LOCATION"R1533"
$SEC"1"
CDS_SEC"1"
VALUE"0"
PACK_TYPE"0402LF"
PART_NUMBER"CS00002JB38"
TOLERANCE"5%"
MATERIAL"CHIP"
WATTAGE"1/16W"
CDS_LIB"pure_quanta";
"B"
$PN"2"25;
"A"
$PN"1"23;
%"GND"
"1","(-8550,4150)","0","pure_quanta_power","I95";
;
CDS_LIB"pure_quanta_power"
SIZE"1B"
HDL_POWER"GND";
"A<SIZE-1..0>\NAC"9;
%"GND"
"1","(-8675,4150)","0","pure_quanta_power","I96";
;
CDS_LIB"pure_quanta_power"
SIZE"1B"
HDL_POWER"GND";
"A<SIZE-1..0>\NAC"10;
END.
